(kicad_pcb
	(version 20241229)
	(generator "pcbnew")
	(generator_version "9.0")
	(general
		(thickness 1.552)
		(legacy_teardrops no)
	)
	(paper "A4")
	(title_block
		(date "2023-07-25")
		(rev "1.1.4")
		(comment 9 "footprints 62-66 of 379")
	)
	(layers
		(0 "F.Cu" signal)
		(4 "In1.Cu" signal)
		(6 "In2.Cu" signal)
		(8 "In3.Cu" signal)
		(10 "In4.Cu" signal)
		(12 "In5.Cu" signal)
		(14 "In6.Cu" signal)
		(2 "B.Cu" signal)
		(9 "F.Adhes" user "F.Adhesive")
		(11 "B.Adhes" user "B.Adhesive")
		(13 "F.Paste" user)
		(15 "B.Paste" user)
		(5 "F.SilkS" user "F.Silkscreen")
		(7 "B.SilkS" user "B.Silkscreen")
		(1 "F.Mask" user)
		(3 "B.Mask" user)
		(17 "Dwgs.User" user "User.Drawings")
		(19 "Cmts.User" user "User.Comments")
		(21 "Eco1.User" user "User.Eco1")
		(23 "Eco2.User" user "User.Eco2")
		(25 "Edge.Cuts" user)
		(27 "Margin" user)
		(31 "F.CrtYd" user "F.Courtyard")
		(29 "B.CrtYd" user "B.Courtyard")
		(35 "F.Fab" user)
		(33 "B.Fab" user)
	)
	(footprint "antmicro-footprints:C_0603_1608Metric"
		(layer "F.Cu")
		(at 144.39 65.34)
		(descr "Capacitor SMD 0603")
		(tags "capacitor 0603")
		(property "Reference" "C24"
			(at -7.56 0.1 0)
			(layer "F.SilkS")
			(effects
				(font
					(size 0.65 0.65)
					(thickness 0.15)
				)
				(justify left bottom)
			)
		)
		(property "Value" "C_22u_0603"
			(at 0 1.6 0)
			(layer "F.Fab")
			(hide yes)
			(effects
				(font
					(size 0.7 0.7)
					(thickness 0.15)
				)
				(justify left bottom)
			)
		)
		(property "Datasheet" "https://www.murata.com/products/productdetail?partno=GRM188R60J226MEA0%23"
			(at 0 0 0)
			(layer "F.Fab")
			(hide yes)
			(effects
				(font
					(size 1.27 1.27)
					(thickness 0.15)
				)
			)
		)
		(property "Description" "SMD Multilayer Ceramic Capacitor, 22 µF, 6.3 V, 0603 [1608 Metric], ± 20%, X5R, GRM Series"
			(at 0 0 0)
			(layer "F.Fab")
			(hide yes)
			(effects
				(font
					(size 1.27 1.27)
					(thickness 0.15)
				)
			)
		)
		(property "Author" "Antmicro"
			(at 0 0 0)
			(layer "F.Fab")
			(hide yes)
			(effects
				(font
					(size 1 1)
					(thickness 0.15)
				)
			)
		)
		(property "Dielectric" ""
			(at 0 0 0)
			(layer "F.Fab")
			(hide yes)
			(effects
				(font
					(size 1 1)
					(thickness 0.15)
				)
			)
		)
		(property "License" "Apache-2.0"
			(at 0 0 0)
			(layer "F.Fab")
			(hide yes)
			(effects
				(font
					(size 1 1)
					(thickness 0.15)
				)
			)
		)
		(property "MPN" "GRM188R60J226MEA0D"
			(at 0 0 0)
			(layer "F.Fab")
			(hide yes)
			(effects
				(font
					(size 1 1)
					(thickness 0.15)
				)
			)
		)
		(property "Manufacturer" "Murata"
			(at 0 0 0)
			(layer "F.Fab")
			(hide yes)
			(effects
				(font
					(size 1 1)
					(thickness 0.15)
				)
			)
		)
		(property "Val" "22u"
			(at 0 0 0)
			(layer "F.Fab")
			(hide yes)
			(effects
				(font
					(size 1 1)
					(thickness 0.15)
				)
			)
		)
		(property "Voltage" ""
			(at 0 0 0)
			(layer "F.Fab")
			(hide yes)
			(effects
				(font
					(size 1 1)
					(thickness 0.15)
				)
			)
		)
		(sheetname "/Power Supply/")
		(sheetfile "supply.kicad_sch")
		(attr smd)
		(fp_line
			(start -0.15 -0.4)
			(end 0.15 -0.4)
			(stroke
				(width 0.15)
				(type solid)
			)
			(layer "F.SilkS")
		)
		(fp_line
			(start -0.15 0.4)
			(end 0.15 0.4)
			(stroke
				(width 0.15)
				(type solid)
			)
			(layer "F.SilkS")
		)
		(fp_rect
			(start -1.25 -0.65)
			(end 1.25 0.65)
			(stroke
				(width 0.05)
				(type solid)
			)
			(fill no)
			(layer "F.CrtYd")
		)
		(fp_rect
			(start -0.8 -0.4)
			(end 0.8 0.4)
			(stroke
				(width 0.15)
				(type solid)
			)
			(fill no)
			(layer "F.Fab")
		)
		(fp_text user "Author: Antmicro"
			(at -1.682 4.894 0)
			(layer "F.Fab")
			(effects
				(font
					(size 0.7 0.7)
					(thickness 0.15)
				)
				(justify left bottom)
			)
		)
		(fp_text user "${REFERENCE}"
			(at -1.682 3.895 0)
			(layer "F.Fab")
			(effects
				(font
					(size 0.7 0.7)
					(thickness 0.15)
				)
				(justify left bottom)
			)
		)
		(fp_text user "License: Apache-2.0"
			(at -1.682 5.895 0)
			(layer "F.Fab")
			(effects
				(font
					(size 0.7 0.7)
					(thickness 0.15)
				)
				(justify left bottom)
			)
		)
		(pad "1" smd roundrect
			(at -0.7 0)
			(size 0.8 1)
			(layers "F.Cu" "F.Mask" "F.Paste")
			(roundrect_rratio 0.2)
			(net 274 "/Power Supply/1V5_OUT")
			(pintype "passive")
		)
		(pad "2" smd roundrect
			(at 0.7 0)
			(size 0.8 1)
			(layers "F.Cu" "F.Mask" "F.Paste")
			(roundrect_rratio 0.2)
			(net 1 "GND")
			(pintype "passive")
		)
	)
	(footprint "antmicro-footprints:R_0402_1005Metric"
		(layer "F.Cu")
		(at 144.94 112.75 180)
		(descr "Resistor SMD 0402")
		(tags "resistor SMD 0402")
		(property "Reference" "R21"
			(at -0.89 -0.39 180)
			(layer "F.SilkS")
			(effects
				(font
					(size 0.65 0.65)
					(thickness 0.15)
				)
				(justify left bottom)
			)
		)
		(property "Value" "R_0R_0402"
			(at 0 1.4 180)
			(layer "F.Fab")
			(hide yes)
			(effects
				(font
					(size 0.7 0.7)
					(thickness 0.15)
				)
				(justify left bottom)
			)
		)
		(property "Datasheet" "https://industrial.panasonic.com/cdbs/www-data/pdf/RDA0000/AOA0000C301.pdf"
			(at 0 0 180)
			(layer "F.Fab")
			(hide yes)
			(effects
				(font
					(size 1.27 1.27)
					(thickness 0.15)
				)
			)
		)
		(property "Description" "SMD Chip Resistor, Jumper, 0 ohm, 100 mW, 0402 [1005 Metric], Thick Film, General Purpose"
			(at 0 0 180)
			(layer "F.Fab")
			(hide yes)
			(effects
				(font
					(size 1.27 1.27)
					(thickness 0.15)
				)
			)
		)
		(property "Author" "Antmicro"
			(at 289.88 225.5 0)
			(layer "F.Fab")
			(hide yes)
			(effects
				(font
					(size 1 1)
					(thickness 0.15)
				)
			)
		)
		(property "Current" "1A"
			(at 289.88 225.5 0)
			(layer "F.Fab")
			(hide yes)
			(effects
				(font
					(size 1 1)
					(thickness 0.15)
				)
			)
		)
		(property "License" "Apache-2.0"
			(at 289.88 225.5 0)
			(layer "F.Fab")
			(hide yes)
			(effects
				(font
					(size 1 1)
					(thickness 0.15)
				)
			)
		)
		(property "MPN" "ERJ2GE0R00X"
			(at 289.88 225.5 0)
			(layer "F.Fab")
			(hide yes)
			(effects
				(font
					(size 1 1)
					(thickness 0.15)
				)
			)
		)
		(property "Manufacturer" "Panasonic"
			(at 289.88 225.5 0)
			(layer "F.Fab")
			(hide yes)
			(effects
				(font
					(size 1 1)
					(thickness 0.15)
				)
			)
		)
		(property "Tolerance" "~"
			(at 289.88 225.5 0)
			(layer "F.Fab")
			(hide yes)
			(effects
				(font
					(size 1 1)
					(thickness 0.15)
				)
			)
		)
		(property "Val" "0R"
			(at 289.88 225.5 0)
			(layer "F.Fab")
			(hide yes)
			(effects
				(font
					(size 1 1)
					(thickness 0.15)
				)
			)
		)
		(sheetname "/Power Supply/")
		(sheetfile "supply.kicad_sch")
		(attr smd)
		(fp_rect
			(start -0.925 -0.47)
			(end 0.925 0.47)
			(stroke
				(width 0.05)
				(type default)
			)
			(fill no)
			(layer "F.CrtYd")
		)
		(fp_rect
			(start -0.5 -0.25)
			(end 0.5 0.25)
			(stroke
				(width 0.15)
				(type solid)
			)
			(fill no)
			(layer "F.Fab")
		)
		(fp_text user "License: Apache-2.0"
			(at -0.95 5.169 180)
			(layer "F.Fab")
			(effects
				(font
					(size 0.7 0.7)
					(thickness 0.15)
				)
				(justify left bottom)
			)
		)
		(fp_text user "${REFERENCE}"
			(at -0.95 3.168 180)
			(layer "F.Fab")
			(effects
				(font
					(size 0.7 0.7)
					(thickness 0.15)
				)
				(justify left bottom)
			)
		)
		(fp_text user "Author: Antmicro"
			(at -0.95 4.169 180)
			(layer "F.Fab")
			(effects
				(font
					(size 0.7 0.7)
					(thickness 0.15)
				)
				(justify left bottom)
			)
		)
		(pad "1" smd roundrect
			(at -0.48 0 180)
			(size 0.59 0.64)
			(layers "F.Cu" "F.Mask" "F.Paste")
			(roundrect_rratio 0.25)
			(net 2 "+3V3")
			(pintype "passive")
		)
		(pad "2" smd roundrect
			(at 0.48 0 180)
			(size 0.59 0.64)
			(layers "F.Cu" "F.Mask" "F.Paste")
			(roundrect_rratio 0.25)
			(net 266 "Net-(U10-V_{IN})")
			(pintype "passive")
		)
	)
	(footprint "antmicro-footprints:R_0402_1005Metric"
		(layer "F.Cu")
		(at 140.64 104.55)
		(descr "Resistor SMD 0402")
		(tags "resistor SMD 0402")
		(property "Reference" "R32"
			(at -1.01 -0.7 0)
			(layer "F.SilkS")
			(effects
				(font
					(size 0.65 0.65)
					(thickness 0.15)
				)
				(justify left bottom)
			)
		)
		(property "Value" "R_10k_0402"
			(at 0 1.4 0)
			(layer "F.Fab")
			(hide yes)
			(effects
				(font
					(size 0.7 0.7)
					(thickness 0.15)
				)
				(justify left bottom)
			)
		)
		(property "Datasheet" "https://www.bourns.com/docs/product-datasheets/cr.pdf"
			(at 0 0 0)
			(layer "F.Fab")
			(hide yes)
			(effects
				(font
					(size 1.27 1.27)
					(thickness 0.15)
				)
			)
		)
		(property "Description" "SMD Chip Resistor, 10 kohm, ± 1%, 62.5 mW, 0402 [1005 Metric], Thick Film, General Purpose"
			(at 0 0 0)
			(layer "F.Fab")
			(hide yes)
			(effects
				(font
					(size 1.27 1.27)
					(thickness 0.15)
				)
			)
		)
		(property "Author" "Antmicro"
			(at 0 0 0)
			(layer "F.Fab")
			(hide yes)
			(effects
				(font
					(size 1 1)
					(thickness 0.15)
				)
			)
		)
		(property "License" "Apache-2.0"
			(at 0 0 0)
			(layer "F.Fab")
			(hide yes)
			(effects
				(font
					(size 1 1)
					(thickness 0.15)
				)
			)
		)
		(property "MPN" "CR0402-FX-1002GLF"
			(at 0 0 0)
			(layer "F.Fab")
			(hide yes)
			(effects
				(font
					(size 1 1)
					(thickness 0.15)
				)
			)
		)
		(property "Manufacturer" "Bourns"
			(at 0 0 0)
			(layer "F.Fab")
			(hide yes)
			(effects
				(font
					(size 1 1)
					(thickness 0.15)
				)
			)
		)
		(property "Tolerance" "1%"
			(at 0 0 0)
			(layer "F.Fab")
			(hide yes)
			(effects
				(font
					(size 1 1)
					(thickness 0.15)
				)
			)
		)
		(property "Val" "10k"
			(at 0 0 0)
			(layer "F.Fab")
			(hide yes)
			(effects
				(font
					(size 1 1)
					(thickness 0.15)
				)
			)
		)
		(sheetname "/Power Supply/")
		(sheetfile "supply.kicad_sch")
		(attr smd)
		(fp_rect
			(start -0.925 -0.47)
			(end 0.925 0.47)
			(stroke
				(width 0.05)
				(type default)
			)
			(fill no)
			(layer "F.CrtYd")
		)
		(fp_rect
			(start -0.5 -0.25)
			(end 0.5 0.25)
			(stroke
				(width 0.15)
				(type solid)
			)
			(fill no)
			(layer "F.Fab")
		)
		(fp_text user "${REFERENCE}"
			(at -0.95 3.168 0)
			(layer "F.Fab")
			(effects
				(font
					(size 0.7 0.7)
					(thickness 0.15)
				)
				(justify left bottom)
			)
		)
		(fp_text user "Author: Antmicro"
			(at -0.95 4.169 0)
			(layer "F.Fab")
			(effects
				(font
					(size 0.7 0.7)
					(thickness 0.15)
				)
				(justify left bottom)
			)
		)
		(fp_text user "License: Apache-2.0"
			(at -0.95 5.169 0)
			(layer "F.Fab")
			(effects
				(font
					(size 0.7 0.7)
					(thickness 0.15)
				)
				(justify left bottom)
			)
		)
		(pad "1" smd roundrect
			(at -0.48 0)
			(size 0.59 0.64)
			(layers "F.Cu" "F.Mask" "F.Paste")
			(roundrect_rratio 0.25)
			(net 1 "GND")
			(pintype "passive")
		)
		(pad "2" smd roundrect
			(at 0.48 0)
			(size 0.59 0.64)
			(layers "F.Cu" "F.Mask" "F.Paste")
			(roundrect_rratio 0.25)
			(net 280 "Net-(U8-ADJ)")
			(pintype "passive")
		)
	)
	(footprint "antmicro-footprints:C_0603_1608Metric"
		(layer "F.Cu")
		(at 148.23 74.84 180)
		(descr "Capacitor SMD 0603")
		(tags "capacitor 0603")
		(property "Reference" "C32"
			(at -3.4 -0.4 0)
			(layer "F.SilkS")
			(effects
				(font
					(size 0.65 0.65)
					(thickness 0.15)
				)
				(justify right bottom)
			)
		)
		(property "Value" "C_22u_0603"
			(at 0 1.6 0)
			(layer "F.Fab")
			(hide yes)
			(effects
				(font
					(size 0.7 0.7)
					(thickness 0.15)
				)
				(justify right bottom)
			)
		)
		(property "Datasheet" "https://www.murata.com/products/productdetail?partno=GRM188R60J226MEA0%23"
			(at 0 0 180)
			(layer "F.Fab")
			(hide yes)
			(effects
				(font
					(size 1.27 1.27)
					(thickness 0.15)
				)
			)
		)
		(property "Description" "SMD Multilayer Ceramic Capacitor, 22 µF, 6.3 V, 0603 [1608 Metric], ± 20%, X5R, GRM Series"
			(at 0 0 180)
			(layer "F.Fab")
			(hide yes)
			(effects
				(font
					(size 1.27 1.27)
					(thickness 0.15)
				)
			)
		)
		(property "Author" "Antmicro"
			(at 296.46 149.68 0)
			(layer "F.Fab")
			(hide yes)
			(effects
				(font
					(size 1 1)
					(thickness 0.15)
				)
			)
		)
		(property "Dielectric" ""
			(at 296.46 149.68 0)
			(layer "F.Fab")
			(hide yes)
			(effects
				(font
					(size 1 1)
					(thickness 0.15)
				)
			)
		)
		(property "License" "Apache-2.0"
			(at 296.46 149.68 0)
			(layer "F.Fab")
			(hide yes)
			(effects
				(font
					(size 1 1)
					(thickness 0.15)
				)
			)
		)
		(property "MPN" "GRM188R60J226MEA0D"
			(at 296.46 149.68 0)
			(layer "F.Fab")
			(hide yes)
			(effects
				(font
					(size 1 1)
					(thickness 0.15)
				)
			)
		)
		(property "Manufacturer" "Murata"
			(at 296.46 149.68 0)
			(layer "F.Fab")
			(hide yes)
			(effects
				(font
					(size 1 1)
					(thickness 0.15)
				)
			)
		)
		(property "Val" "22u"
			(at 296.46 149.68 0)
			(layer "F.Fab")
			(hide yes)
			(effects
				(font
					(size 1 1)
					(thickness 0.15)
				)
			)
		)
		(property "Voltage" ""
			(at 296.46 149.68 0)
			(layer "F.Fab")
			(hide yes)
			(effects
				(font
					(size 1 1)
					(thickness 0.15)
				)
			)
		)
		(sheetname "/Power Supply/")
		(sheetfile "supply.kicad_sch")
		(attr smd)
		(fp_line
			(start -0.15 0.4)
			(end 0.15 0.4)
			(stroke
				(width 0.15)
				(type solid)
			)
			(layer "F.SilkS")
		)
		(fp_line
			(start -0.15 -0.4)
			(end 0.15 -0.4)
			(stroke
				(width 0.15)
				(type solid)
			)
			(layer "F.SilkS")
		)
		(fp_rect
			(start -1.25 -0.65)
			(end 1.25 0.65)
			(stroke
				(width 0.05)
				(type solid)
			)
			(fill no)
			(layer "F.CrtYd")
		)
		(fp_rect
			(start -0.8 -0.4)
			(end 0.8 0.4)
			(stroke
				(width 0.15)
				(type solid)
			)
			(fill no)
			(layer "F.Fab")
		)
		(fp_text user "${REFERENCE}"
			(at -1.682 3.895 180)
			(layer "F.Fab")
			(effects
				(font
					(size 0.7 0.7)
					(thickness 0.15)
				)
				(justify left bottom)
			)
		)
		(fp_text user "Author: Antmicro"
			(at -1.682 4.894 180)
			(layer "F.Fab")
			(effects
				(font
					(size 0.7 0.7)
					(thickness 0.15)
				)
				(justify left bottom)
			)
		)
		(fp_text user "License: Apache-2.0"
			(at -1.682 5.895 180)
			(layer "F.Fab")
			(effects
				(font
					(size 0.7 0.7)
					(thickness 0.15)
				)
				(justify left bottom)
			)
		)
		(pad "1" smd roundrect
			(at -0.7 0 180)
			(size 0.8 1)
			(layers "F.Cu" "F.Mask" "F.Paste")
			(roundrect_rratio 0.2)
			(net 1 "GND")
			(pintype "passive")
		)
		(pad "2" smd roundrect
			(at 0.7 0 180)
			(size 0.8 1)
			(layers "F.Cu" "F.Mask" "F.Paste")
			(roundrect_rratio 0.2)
			(net 273 "/Power Supply/1V0_OUT")
			(pintype "passive")
		)
	)
	(footprint "antmicro-footprints:C_Pol_0603_1608Metric"
		(layer "F.Cu")
		(at 94.3 70.515 90)
		(property "Reference" "C71"
			(at 1.375 0.23 90)
			(layer "F.SilkS")
			(effects
				(font
					(size 0.65 0.65)
					(thickness 0.15)
				)
				(justify left bottom)
			)
		)
		(property "Value" "C_33u_0603"
			(at 0 1.6 90)
			(layer "F.Fab")
			(hide yes)
			(effects
				(font
					(size 0.7 0.7)
					(thickness 0.15)
				)
				(justify left bottom)
			)
		)
		(property "Datasheet" "https://spicat.kyocera-avx.com/product/tan/chartview/F980G336MMA/"
			(at 0 0 90)
			(layer "F.Fab")
			(hide yes)
			(effects
				(font
					(size 1.27 1.27)
					(thickness 0.15)
				)
			)
		)
		(property "Description" "Surface Mount Tantalum Capacitor, 33 µF, 4 V, 0603 [1608 Metric], ± 20%, 4 ohm, M"
			(at 0 0 90)
			(layer "F.Fab")
			(hide yes)
			(effects
				(font
					(size 1.27 1.27)
					(thickness 0.15)
				)
			)
		)
		(property "Author" "Antmicro"
			(at 164.815 -23.785 0)
			(layer "F.Fab")
			(hide yes)
			(effects
				(font
					(size 1 1)
					(thickness 0.15)
				)
			)
		)
		(property "Dielectric" "template_dielectric"
			(at 164.815 -23.785 0)
			(layer "F.Fab")
			(hide yes)
			(effects
				(font
					(size 1 1)
					(thickness 0.15)
				)
			)
		)
		(property "License" "Apache-2.0"
			(at 164.815 -23.785 0)
			(layer "F.Fab")
			(hide yes)
			(effects
				(font
					(size 1 1)
					(thickness 0.15)
				)
			)
		)
		(property "MPN" "F980G336MMA"
			(at 164.815 -23.785 0)
			(layer "F.Fab")
			(hide yes)
			(effects
				(font
					(size 1 1)
					(thickness 0.15)
				)
			)
		)
		(property "Manufacturer" "KYOCERA AVX"
			(at 164.815 -23.785 0)
			(layer "F.Fab")
			(hide yes)
			(effects
				(font
					(size 1 1)
					(thickness 0.15)
				)
			)
		)
		(property "Val" "33u"
			(at 164.815 -23.785 0)
			(layer "F.Fab")
			(hide yes)
			(effects
				(font
					(size 1 1)
					(thickness 0.15)
				)
			)
		)
		(property "Voltage" "4V"
			(at 164.815 -23.785 0)
			(layer "F.Fab")
			(hide yes)
			(effects
				(font
					(size 1 1)
					(thickness 0.15)
				)
			)
		)
		(sheetname "/SDI/")
		(sheetfile "sdi.kicad_sch")
		(attr smd)
		(fp_line
			(start -1.2 -0.775)
			(end -1.2 -0.475)
			(stroke
				(width 0.12)
				(type solid)
			)
			(layer "F.SilkS")
		)
		(fp_line
			(start -1.35 -0.625)
			(end -1.05 -0.625)
			(stroke
				(width 0.12)
				(type solid)
			)
			(layer "F.SilkS")
		)
		(fp_line
			(start -0.15 -0.4)
			(end 0.15 -0.4)
			(stroke
				(width 0.15)
				(type solid)
			)
			(layer "F.SilkS")
		)
		(fp_line
			(start -0.15 0.4)
			(end 0.15 0.4)
			(stroke
				(width 0.15)
				(type solid)
			)
			(layer "F.SilkS")
		)
		(fp_rect
			(start -1.25 -0.65)
			(end 1.25 0.65)
			(stroke
				(width 0.05)
				(type solid)
			)
			(fill no)
			(layer "F.CrtYd")
		)
		(fp_text user "Author: Antmicro"
			(at -1.25 3.77 90)
			(layer "F.Fab")
			(effects
				(font
					(size 0.7 0.7)
					(thickness 0.15)
				)
				(justify left bottom)
			)
		)
		(fp_text user "${REFERENCE}"
			(at -1.25 6.17 90)
			(layer "F.Fab")
			(effects
				(font
					(size 0.7 0.7)
					(thickness 0.15)
				)
				(justify left bottom)
			)
		)
		(fp_text user "License: Apache-2.0"
			(at -1.25 4.97 90)
			(layer "F.Fab")
			(effects
				(font
					(size 0.7 0.7)
					(thickness 0.15)
				)
				(justify left bottom)
			)
		)
		(pad "1" smd roundrect
			(at -0.7 0 90)
			(size 0.8 1)
			(layers "F.Cu" "F.Mask" "F.Paste")
			(roundrect_rratio 0.2)
			(net 244 "Net-(U15C-VCO_{VDD})")
			(pintype "passive")
		)
		(pad "2" smd roundrect
			(at 0.7 0 90)
			(size 0.8 1)
			(layers "F.Cu" "F.Mask" "F.Paste")
			(roundrect_rratio 0.2)
			(net 1 "GND")
			(pintype "passive")
		)
	)
)
